# TIMECARD (Time Appliance Project (Time Card)) — schematic netlist excerpt (pin names and nets, part order shuffled) for the footprints in the layout excerpt that follows; sources: Cadence DE-HDL packaged netlist, KiCad conversion of R4006-B0001-02_R01.brd

C59  CAPACITOR  0.1UF 25V 10%  pkg SMC_0402R_H022  page 21 : \1\ = XP5R0V_MAC ; \2\ = SG
L3  FERRITEBEAD  26OHM 25%  pkg SMC_0603R_H030  page 21 : \1\ = XP5R0V_MAC ; \2\ = XP5R0V

(kicad_pcb
	(version 20260206)
	(generator "pcbnew")
	(generator_version "10.0")
	(general
		(thickness 1.6)
		(legacy_teardrops no)
	)
	(paper "A4")
	(title_block
		(title "timecard-production-celestica-r4006 — R4006-B0001-02_R01.brd")
		(comment 1 "Time Appliance Project (Time Card) / footprints 804-805 of 1113")
	)
	(layers
		(0 "F.Cu" signal "TOP")
		(4 "In1.Cu" signal "L02_GND1")
		(6 "In2.Cu" signal "L03_SIG1")
		(8 "In3.Cu" signal "L04_GND2")
		(10 "In4.Cu" signal "L05_VCC1")
		(12 "In5.Cu" signal "L06_VCC2")
		(14 "In6.Cu" signal "L07_GND3")
		(16 "In7.Cu" signal "L08_SIG2")
		(18 "In8.Cu" signal "L09_GND4")
		(2 "B.Cu" signal "BOTTOM")
		(9 "F.Adhes" user "F.Adhesive")
		(11 "B.Adhes" user "B.Adhesive")
		(13 "F.Paste" user "Package Geometry/Pastemask Top")
		(15 "B.Paste" user "Package Geometry/Pastemask Bottom")
		(5 "F.SilkS" user "Ref Des/Silkscreen Top")
		(7 "B.SilkS" user "Ref Des/Silkscreen Bottom")
		(1 "F.Mask" user "Board Geometry/Soldermask Top")
		(3 "B.Mask" user "Board Geometry/Soldermask Bottom")
		(17 "Dwgs.User" user "User.Drawings")
		(19 "Cmts.User" user "User.Comments")
		(21 "Eco1.User" user "User.Eco1")
		(23 "Eco2.User" user "User.Eco2")
		(25 "Edge.Cuts" user "Board Geometry/Outline")
		(27 "Margin" user)
		(31 "F.CrtYd" user "Package Geometry/Place Bound Top")
		(29 "B.CrtYd" user "Package Geometry/Place Bound Bottom")
		(35 "F.Fab" user "Ref Des/Assembly Top")
		(33 "B.Fab" user "Ref Des/Assembly Bottom")
	)
	(footprint ""
		(layer "B.Cu")
		(at 72.517 -72.771 -90)
		(property "Reference" "C59"
			(at -3.81 -0.59563 270)
			(unlocked yes)
			(layer "B.SilkS")
			(effects
				(font
					(size 0.7874 0.5842)
					(thickness 0.1524)
				)
				(justify mirror)
			)
		)
		(property "Value" "VAL*"
			(at -0.0762 2.067306 270)
			(unlocked yes)
			(layer "B.Fab")
			(hide yes)
			(effects
				(font
					(size 0.7874 0.5842)
					(thickness 0.1524)
				)
				(justify mirror)
			)
		)
		(property "Tolerance" "TOL*"
			(at -0.0762 3.032506 270)
			(unlocked yes)
			(layer "Cmts.User")
			(hide yes)
			(effects
				(font
					(size 0.7874 0.5842)
					(thickness 0.1524)
				)
				(justify mirror)
			)
		)
		(property "User Part Number" "PARTNUM*"
			(at -0.1016 4.023106 270)
			(unlocked yes)
			(layer "Cmts.User")
			(hide yes)
			(effects
				(font
					(size 0.7874 0.5842)
					(thickness 0.1524)
				)
				(justify mirror)
			)
		)
		(property "Device Type" "CAPACITOR-G105-0B104-EK,0.1UF,A"
			(at -0.0508 1.127506 270)
			(unlocked yes)
			(layer "B.Fab")
			(hide yes)
			(effects
				(font
					(size 0.7874 0.5842)
					(thickness 0.1524)
				)
				(justify mirror)
			)
		)
		(duplicate_pad_numbers_are_jumpers no)
		(fp_line
			(start -1.143 0.5588)
			(end -1.143 -0.5588)
			(stroke
				(width 0.1)
				(type default)
			)
			(layer "B.SilkS")
		)
		(fp_line
			(start 1.143 0.5588)
			(end -1.143 0.5588)
			(stroke
				(width 0.1)
				(type default)
			)
			(layer "B.SilkS")
		)
		(fp_line
			(start -1.143 -0.5588)
			(end 1.143 -0.5588)
			(stroke
				(width 0.1)
				(type default)
			)
			(layer "B.SilkS")
		)
		(fp_line
			(start 1.143 -0.5588)
			(end 1.143 0.5588)
			(stroke
				(width 0.1)
				(type default)
			)
			(layer "B.SilkS")
		)
		(fp_rect
			(start 1.143 -0.5588)
			(end -1.143 0.5588)
			(stroke
				(width 0)
				(type default)
			)
			(fill no)
			(layer "B.CrtYd")
		)
		(fp_line
			(start -0.508 0.3048)
			(end -0.508 -0.3048)
			(stroke
				(width 0.1)
				(type default)
			)
			(layer "B.Fab")
		)
		(fp_line
			(start 0.508 0.3048)
			(end -0.508 0.3048)
			(stroke
				(width 0.1)
				(type default)
			)
			(layer "B.Fab")
		)
		(fp_line
			(start -0.508 -0.3048)
			(end 0.508 -0.3048)
			(stroke
				(width 0.1)
				(type default)
			)
			(layer "B.Fab")
		)
		(fp_line
			(start 0.508 -0.3048)
			(end 0.508 0.3048)
			(stroke
				(width 0.1)
				(type default)
			)
			(layer "B.Fab")
		)
		(pad "1" smd rect
			(at 0.5334 0 90)
			(size 0.7112 0.6096)
			(layers "B.Cu" "B.Mask" "B.Paste")
			(net "XP5R0V_MAC")
		)
		(pad "2" smd rect
			(at -0.5334 0 90)
			(size 0.7112 0.6096)
			(layers "B.Cu" "B.Mask" "B.Paste")
			(net "SG")
		)
		(zone
			(layer "B.Cu")
			(hatch none 0.5)
			(connect_pads
				(clearance 0)
			)
			(min_thickness 0.25)
			(keepout
				(tracks allowed)
				(vias not_allowed)
				(pads allowed)
				(copperpour not_allowed)
				(footprints allowed)
			)
			(placement
				(enabled no)
				(sheetname "")
			)
			(fill
				(thermal_gap 0.5)
				(thermal_bridge_width 0.5)
				(island_removal_mode 0)
			)
			(polygon
				(pts
					(xy 72.8218 -72.6948) (xy 72.8218 -72.8472) (xy 72.2122 -72.8472) (xy 72.2122 -72.6948)
				)
			)
		)
	)
	(footprint ""
		(layer "B.Cu")
		(at 80.899 -73.152 -90)
		(property "Reference" "L3"
			(at -2.3622 0.29337 270)
			(unlocked yes)
			(layer "B.SilkS")
			(effects
				(font
					(size 0.7874 0.5842)
					(thickness 0.1524)
				)
				(justify left mirror)
			)
		)
		(property "Value" "VAL*"
			(at 0.9398 3.70967 270)
			(unlocked yes)
			(layer "B.Fab")
			(hide yes)
			(effects
				(font
					(size 0.7874 0.5842)
					(thickness 0.1524)
				)
				(justify left mirror)
			)
		)
		(property "Tolerance" "TOL*"
			(at 0.9906 5.00507 270)
			(unlocked yes)
			(layer "Cmts.User")
			(hide yes)
			(effects
				(font
					(size 0.7874 0.5842)
					(thickness 0.1524)
				)
				(justify left mirror)
			)
		)
		(property "User Part Number" "PARTNUM*"
			(at 2.54 2.46507 270)
			(unlocked yes)
			(layer "Cmts.User")
			(hide yes)
			(effects
				(font
					(size 0.7874 0.5842)
					(thickness 0.1524)
				)
				(justify left mirror)
			)
		)
		(property "Device Type" "FERRITEBEAD-G191-10101-01,26OHA"
			(at 0.9906 1.22047 270)
			(unlocked yes)
			(layer "B.Fab")
			(hide yes)
			(effects
				(font
					(size 0.7874 0.5842)
					(thickness 0.1524)
				)
				(justify left mirror)
			)
		)
		(duplicate_pad_numbers_are_jumpers no)
		(fp_line
			(start -1.3208 0.7112)
			(end 1.3208 0.7112)
			(stroke
				(width 0.1)
				(type default)
			)
			(layer "B.SilkS")
		)
		(fp_line
			(start 1.3208 0.7112)
			(end 1.3208 -0.7112)
			(stroke
				(width 0.1)
				(type default)
			)
			(layer "B.SilkS")
		)
		(fp_line
			(start -1.3208 -0.7112)
			(end -1.3208 0.7112)
			(stroke
				(width 0.1)
				(type default)
			)
			(layer "B.SilkS")
		)
		(fp_line
			(start 1.3208 -0.7112)
			(end -1.3208 -0.7112)
			(stroke
				(width 0.1)
				(type default)
			)
			(layer "B.SilkS")
		)
		(fp_rect
			(start 1.3208 0.7112)
			(end -1.3208 -0.7112)
			(stroke
				(width 0)
				(type default)
			)
			(fill no)
			(layer "B.CrtYd")
		)
		(fp_line
			(start -0.8128 0.4572)
			(end 0.8128 0.4572)
			(stroke
				(width 0.1)
				(type default)
			)
			(layer "B.Fab")
		)
		(fp_line
			(start 0.8128 0.4572)
			(end 0.8128 -0.4572)
			(stroke
				(width 0.1)
				(type default)
			)
			(layer "B.Fab")
		)
		(fp_line
			(start -0.8128 -0.4572)
			(end -0.8128 0.4572)
			(stroke
				(width 0.1)
				(type default)
			)
			(layer "B.Fab")
		)
		(fp_line
			(start 0.8128 -0.4572)
			(end -0.8128 -0.4572)
			(stroke
				(width 0.1)
				(type default)
			)
			(layer "B.Fab")
		)
		(pad "1" smd rect
			(at 0.6858 0 90)
			(size 0.762 0.8636)
			(layers "B.Cu" "B.Mask" "B.Paste")
			(net "XP5R0V_MAC")
		)
		(pad "2" smd rect
			(at -0.6858 0 90)
			(size 0.762 0.8636)
			(layers "B.Cu" "B.Mask" "B.Paste")
			(net "XP5R0V")
		)
		(zone
			(layer "B.Cu")
			(hatch none 0.5)
			(connect_pads
				(clearance 0)
			)
			(min_thickness 0.25)
			(keepout
				(tracks not_allowed)
				(vias allowed)
				(pads allowed)
				(copperpour not_allowed)
				(footprints allowed)
			)
			(placement
				(enabled no)
				(sheetname "")
			)
			(fill
				(thermal_gap 0.5)
				(thermal_bridge_width 0.5)
				(island_removal_mode 0)
			)
			(polygon
				(pts
					(xy 80.4418 -72.9996) (xy 81.3562 -72.9996) (xy 81.3562 -73.3044) (xy 80.4418 -73.3044)
				)
			)
		)
		(zone
			(layer "B.Cu")
			(hatch none 0.5)
			(connect_pads
				(clearance 0)
			)
			(min_thickness 0.25)
			(keepout
				(tracks allowed)
				(vias not_allowed)
				(pads allowed)
				(copperpour not_allowed)
				(footprints allowed)
			)
			(placement
				(enabled no)
				(sheetname "")
			)
			(fill
				(thermal_gap 0.5)
				(thermal_bridge_width 0.5)
				(island_removal_mode 0)
			)
			(polygon
				(pts
					(xy 80.4418 -72.9996) (xy 81.3562 -72.9996) (xy 81.3562 -73.3044) (xy 80.4418 -73.3044)
				)
			)
		)
	)
)
